# T6G (Grand Teton) — schematic netlist excerpt (pin names and nets, part order shuffled) for the footprints in the layout excerpt that follows; sources: Cadence DE-HDL packaged netlist, KiCad conversion of 04192023_DAF0TMB3IC0_F0TG_MB_C_brd_V02_OCP.brd

R6710  Q_RES  0 5% CHIP  pkg 0402LF  page 81 : A = RST_RT_CPU1_P0_PERST_R_N ; B = RST_RT_CPU1_P0_PERST_R2_N
PR3929  Q_RES  1K 1% EMPTY  pkg 0402LF  page 262 : A = HSC_ADDR ; B = HSC_VDD18
C6698  Q_CAP_DIFFBUS  DIFF BUS_0.22UF 6.3V 20% X6S  pkg C0201  page 341 : \1\ = P5E_CPU1_P2_TX_BUF_C_DN<2> ; \2\ = P5E_CPU1_P2_TX_BUF_DN<2>

(kicad_pcb
	(version 20260206)
	(generator "pcbnew")
	(generator_version "10.0")
	(general
		(thickness 1.6)
		(legacy_teardrops no)
	)
	(paper "A4")
	(title_block
		(title "04192023_DAF0TMB3IC0_F0TG_MB_C_brd_V02_OCP.brd")
		(comment 1 "Grand Teton / footprints 4209-4211 of 8354")
	)
	(layers
		(0 "F.Cu" signal "TOP")
		(4 "In1.Cu" signal "GND")
		(6 "In2.Cu" signal "IN1")
		(8 "In3.Cu" signal "GND1")
		(10 "In4.Cu" signal "IN2")
		(12 "In5.Cu" signal "GND2")
		(14 "In6.Cu" signal "IN3")
		(16 "In7.Cu" signal "GND3")
		(18 "In8.Cu" signal "VCC")
		(20 "In9.Cu" signal "VCC1")
		(22 "In10.Cu" signal "GND4")
		(24 "In11.Cu" signal "IN4")
		(26 "In12.Cu" signal "GND5")
		(28 "In13.Cu" signal "IN5")
		(30 "In14.Cu" signal "GND6")
		(32 "In15.Cu" signal "IN6")
		(34 "In16.Cu" signal "GND7")
		(2 "B.Cu" signal "BOTTOM")
		(9 "F.Adhes" user "F.Adhesive")
		(11 "B.Adhes" user "B.Adhesive")
		(13 "F.Paste" user "Package Geometry/Pastemask Top")
		(15 "B.Paste" user "Package Geometry/Pastemask Bottom")
		(5 "F.SilkS" user "Ref Des/Silkscreen Top")
		(7 "B.SilkS" user "Ref Des/Silkscreen Bottom")
		(1 "F.Mask" user "Board Geometry/Soldermask Top")
		(3 "B.Mask" user "Board Geometry/Soldermask Bottom")
		(17 "Dwgs.User" user "User.Drawings")
		(19 "Cmts.User" user "User.Comments")
		(21 "Eco1.User" user "User.Eco1")
		(23 "Eco2.User" user "User.Eco2")
		(25 "Edge.Cuts" user "Board Geometry/Outline")
		(27 "Margin" user)
		(31 "F.CrtYd" user "Package Geometry/Place Bound Top")
		(29 "B.CrtYd" user "Package Geometry/Place Bound Bottom")
		(35 "F.Fab" user "Ref Des/Assembly Top")
		(33 "B.Fab" user "Ref Des/Assembly Bottom")
	)
	(footprint ""
		(layer "F.Cu")
		(at 120.995186 -408.517344 -90)
		(property "Reference" "C6698"
			(at 0 0 270)
			(layer "F.SilkS")
			(hide yes)
			(effects
				(font
					(size 1.27 1.27)
				)
			)
		)
		(property "Value" ""
			(at 0 0 270)
			(layer "F.Fab")
			(effects
				(font
					(size 1.27 1.27)
				)
			)
		)
		(duplicate_pad_numbers_are_jumpers no)
		(fp_line
			(start -0.299974 0.150114)
			(end -0.299974 -0.150114)
			(stroke
				(width 0.1)
				(type default)
			)
			(layer "F.Fab")
		)
		(fp_line
			(start 0.299974 0.150114)
			(end -0.299974 0.150114)
			(stroke
				(width 0.1)
				(type default)
			)
			(layer "F.Fab")
		)
		(fp_line
			(start -0.299974 -0.150114)
			(end 0.299974 -0.150114)
			(stroke
				(width 0.1)
				(type default)
			)
			(layer "F.Fab")
		)
		(fp_line
			(start 0.299974 -0.150114)
			(end 0.299974 0.150114)
			(stroke
				(width 0.1)
				(type default)
			)
			(layer "F.Fab")
		)
		(pad "1" smd rect
			(at -0.2667 0 270)
			(size 0.3048 0.381)
			(layers "F.Cu" "F.Mask" "F.Paste")
			(net "P5E_CPU1_P2_TX_BUF_C_DN<2>")
		)
		(pad "2" smd rect
			(at 0.2667 0 270)
			(size 0.3048 0.381)
			(layers "F.Cu" "F.Mask" "F.Paste")
			(net "P5E_CPU1_P2_TX_BUF_DN<2>")
		)
	)
	(footprint ""
		(layer "F.Cu")
		(at 178.985164 -129.366518 -90)
		(property "Reference" "R6710"
			(at 0 0 270)
			(layer "F.SilkS")
			(hide yes)
			(effects
				(font
					(size 1.27 1.27)
				)
			)
		)
		(property "Value" ""
			(at 0 0 270)
			(layer "F.Fab")
			(effects
				(font
					(size 1.27 1.27)
				)
			)
		)
		(duplicate_pad_numbers_are_jumpers no)
		(fp_line
			(start -0.7874 0.4064)
			(end -0.7874 -0.4064)
			(stroke
				(width 0.1524)
				(type default)
			)
			(layer "F.SilkS")
		)
		(fp_line
			(start 0.7874 0.4064)
			(end -0.7874 0.4064)
			(stroke
				(width 0.1524)
				(type default)
			)
			(layer "F.SilkS")
		)
		(fp_line
			(start -0.7874 -0.4064)
			(end 0.7874 -0.4064)
			(stroke
				(width 0.1524)
				(type default)
			)
			(layer "F.SilkS")
		)
		(fp_line
			(start 0.7874 -0.4064)
			(end 0.7874 0.4064)
			(stroke
				(width 0.1524)
				(type default)
			)
			(layer "F.SilkS")
		)
		(fp_line
			(start -0.67945 0.3048)
			(end -0.67945 -0.305054)
			(stroke
				(width 0.1)
				(type default)
			)
			(layer "F.Fab")
		)
		(fp_line
			(start -0.12065 0.3048)
			(end -0.67945 0.3048)
			(stroke
				(width 0.1)
				(type default)
			)
			(layer "F.Fab")
		)
		(fp_line
			(start 0.120396 0.3048)
			(end 0.120396 0.2794)
			(stroke
				(width 0.1)
				(type default)
			)
			(layer "F.Fab")
		)
		(fp_line
			(start 0.67945 0.3048)
			(end 0.120396 0.3048)
			(stroke
				(width 0.1)
				(type default)
			)
			(layer "F.Fab")
		)
		(fp_line
			(start -0.12065 0.2794)
			(end -0.12065 0.3048)
			(stroke
				(width 0.1)
				(type default)
			)
			(layer "F.Fab")
		)
		(fp_line
			(start 0.120396 0.2794)
			(end -0.12065 0.2794)
			(stroke
				(width 0.1)
				(type default)
			)
			(layer "F.Fab")
		)
		(fp_line
			(start -0.12065 -0.2794)
			(end 0.12065 -0.2794)
			(stroke
				(width 0.1)
				(type default)
			)
			(layer "F.Fab")
		)
		(fp_line
			(start 0.12065 -0.2794)
			(end 0.12065 -0.3048)
			(stroke
				(width 0.1)
				(type default)
			)
			(layer "F.Fab")
		)
		(fp_line
			(start 0.12065 -0.3048)
			(end 0.67945 -0.3048)
			(stroke
				(width 0.1)
				(type default)
			)
			(layer "F.Fab")
		)
		(fp_line
			(start 0.67945 -0.3048)
			(end 0.67945 0.3048)
			(stroke
				(width 0.1)
				(type default)
			)
			(layer "F.Fab")
		)
		(fp_line
			(start -0.67945 -0.305054)
			(end -0.12065 -0.305054)
			(stroke
				(width 0.1)
				(type default)
			)
			(layer "F.Fab")
		)
		(fp_line
			(start -0.12065 -0.305054)
			(end -0.12065 -0.2794)
			(stroke
				(width 0.1)
				(type default)
			)
			(layer "F.Fab")
		)
		(pad "1" smd circle
			(at -0.40005 0 270)
			(size 0 0)
			(layers "F.Cu" "F.Mask" "F.Paste")
			(net "RST_RT_CPU1_P0_PERST_R_N")
		)
		(pad "2" smd circle
			(at 0.40005 0 270)
			(size 0 0)
			(layers "F.Cu" "F.Mask" "F.Paste")
			(net "RST_RT_CPU1_P0_PERST_R2_N")
		)
	)
	(footprint ""
		(layer "F.Cu")
		(at 178.689 -395.351 180)
		(property "Reference" "PR3929"
			(at 0 0 180)
			(layer "F.SilkS")
			(hide yes)
			(effects
				(font
					(size 1.27 1.27)
				)
			)
		)
		(property "Value" ""
			(at 0 0 180)
			(layer "F.Fab")
			(effects
				(font
					(size 1.27 1.27)
				)
			)
		)
		(duplicate_pad_numbers_are_jumpers no)
		(fp_line
			(start 0.7874 0.4064)
			(end -0.7874 0.4064)
			(stroke
				(width 0.1524)
				(type default)
			)
			(layer "F.SilkS")
		)
		(fp_line
			(start 0.7874 -0.4064)
			(end 0.7874 0.4064)
			(stroke
				(width 0.1524)
				(type default)
			)
			(layer "F.SilkS")
		)
		(fp_line
			(start -0.7874 0.4064)
			(end -0.7874 -0.4064)
			(stroke
				(width 0.1524)
				(type default)
			)
			(layer "F.SilkS")
		)
		(fp_line
			(start -0.7874 -0.4064)
			(end 0.7874 -0.4064)
			(stroke
				(width 0.1524)
				(type default)
			)
			(layer "F.SilkS")
		)
		(fp_line
			(start 0.67945 0.3048)
			(end 0.120396 0.3048)
			(stroke
				(width 0.1)
				(type default)
			)
			(layer "F.Fab")
		)
		(fp_line
			(start 0.67945 -0.3048)
			(end 0.67945 0.3048)
			(stroke
				(width 0.1)
				(type default)
			)
			(layer "F.Fab")
		)
		(fp_line
			(start 0.12065 -0.2794)
			(end 0.12065 -0.3048)
			(stroke
				(width 0.1)
				(type default)
			)
			(layer "F.Fab")
		)
		(fp_line
			(start 0.12065 -0.3048)
			(end 0.67945 -0.3048)
			(stroke
				(width 0.1)
				(type default)
			)
			(layer "F.Fab")
		)
		(fp_line
			(start 0.120396 0.3048)
			(end 0.120396 0.2794)
			(stroke
				(width 0.1)
				(type default)
			)
			(layer "F.Fab")
		)
		(fp_line
			(start 0.120396 0.2794)
			(end -0.12065 0.2794)
			(stroke
				(width 0.1)
				(type default)
			)
			(layer "F.Fab")
		)
		(fp_line
			(start -0.12065 0.3048)
			(end -0.67945 0.3048)
			(stroke
				(width 0.1)
				(type default)
			)
			(layer "F.Fab")
		)
		(fp_line
			(start -0.12065 0.2794)
			(end -0.12065 0.3048)
			(stroke
				(width 0.1)
				(type default)
			)
			(layer "F.Fab")
		)
		(fp_line
			(start -0.12065 -0.2794)
			(end 0.12065 -0.2794)
			(stroke
				(width 0.1)
				(type default)
			)
			(layer "F.Fab")
		)
		(fp_line
			(start -0.12065 -0.305054)
			(end -0.12065 -0.2794)
			(stroke
				(width 0.1)
				(type default)
			)
			(layer "F.Fab")
		)
		(fp_line
			(start -0.67945 0.3048)
			(end -0.67945 -0.305054)
			(stroke
				(width 0.1)
				(type default)
			)
			(layer "F.Fab")
		)
		(fp_line
			(start -0.67945 -0.305054)
			(end -0.12065 -0.305054)
			(stroke
				(width 0.1)
				(type default)
			)
			(layer "F.Fab")
		)
		(pad "1" smd circle
			(at -0.40005 0 180)
			(size 0 0)
			(layers "F.Cu" "F.Mask" "F.Paste")
			(net "HSC_ADDR")
		)
		(pad "2" smd circle
			(at 0.40005 0 180)
			(size 0 0)
			(layers "F.Cu" "F.Mask" "F.Paste")
			(net "HSC_VDD18")
		)
	)
)
